(kicad_pcb
	(version 20260206)
	(generator "pcbnew")
	(generator_version "10.0")
	(general
		(thickness 1.6)
		(legacy_teardrops no)
	)
	(paper "A4")
	(title_block
		(title "03242023_DA0F0TMBIJ0_F0T_Motherboard_J_brd_V01_OCP.brd")
		(comment 1 "Grand Teton / footprints 3723-3728 of 6105")
	)
	(layers
		(0 "F.Cu" signal "TOP")
		(4 "In1.Cu" signal "GND")
		(6 "In2.Cu" signal "IN1")
		(8 "In3.Cu" signal "GND1")
		(10 "In4.Cu" signal "IN2")
		(12 "In5.Cu" signal "GND2")
		(14 "In6.Cu" signal "IN3")
		(16 "In7.Cu" signal "GND3")
		(18 "In8.Cu" signal "VCC")
		(20 "In9.Cu" signal "VCC1")
		(22 "In10.Cu" signal "GND4")
		(24 "In11.Cu" signal "IN4")
		(26 "In12.Cu" signal "GND5")
		(28 "In13.Cu" signal "IN5")
		(30 "In14.Cu" signal "GND6")
		(32 "In15.Cu" signal "IN6")
		(34 "In16.Cu" signal "GND7")
		(2 "B.Cu" signal "BOTTOM")
		(9 "F.Adhes" user "F.Adhesive")
		(11 "B.Adhes" user "B.Adhesive")
		(13 "F.Paste" user "Package Geometry/Pastemask Top")
		(15 "B.Paste" user "Package Geometry/Pastemask Bottom")
		(5 "F.SilkS" user "Ref Des/Silkscreen Top")
		(7 "B.SilkS" user "Ref Des/Silkscreen Bottom")
		(1 "F.Mask" user "Board Geometry/Soldermask Top")
		(3 "B.Mask" user "Board Geometry/Soldermask Bottom")
		(17 "Dwgs.User" user "User.Drawings")
		(19 "Cmts.User" user "User.Comments")
		(21 "Eco1.User" user "User.Eco1")
		(23 "Eco2.User" user "User.Eco2")
		(25 "Edge.Cuts" user "Board Geometry/Outline")
		(27 "Margin" user)
		(31 "F.CrtYd" user "Package Geometry/Place Bound Top")
		(29 "B.CrtYd" user "Package Geometry/Place Bound Bottom")
		(35 "F.Fab" user "Ref Des/Assembly Top")
		(33 "B.Fab" user "Ref Des/Assembly Bottom")
	)
	(footprint ""
		(layer "F.Cu")
		(at 124.64288 -92.674948 -90)
		(property "Reference" "R4396"
			(at 0 0 270)
			(layer "F.SilkS")
			(hide yes)
			(effects
				(font
					(size 1.27 1.27)
				)
			)
		)
		(property "Value" ""
			(at 0 0 270)
			(layer "F.Fab")
			(effects
				(font
					(size 1.27 1.27)
				)
			)
		)
		(duplicate_pad_numbers_are_jumpers no)
		(fp_line
			(start -0.7874 0.4064)
			(end -0.7874 -0.4064)
			(stroke
				(width 0.1524)
				(type default)
			)
			(layer "F.SilkS")
		)
		(fp_line
			(start 0.7874 0.4064)
			(end -0.7874 0.4064)
			(stroke
				(width 0.1524)
				(type default)
			)
			(layer "F.SilkS")
		)
		(fp_line
			(start -0.7874 -0.4064)
			(end 0.7874 -0.4064)
			(stroke
				(width 0.1524)
				(type default)
			)
			(layer "F.SilkS")
		)
		(fp_line
			(start 0.7874 -0.4064)
			(end 0.7874 0.4064)
			(stroke
				(width 0.1524)
				(type default)
			)
			(layer "F.SilkS")
		)
		(fp_line
			(start -0.67945 0.3048)
			(end -0.67945 -0.305054)
			(stroke
				(width 0.1)
				(type default)
			)
			(layer "F.Fab")
		)
		(fp_line
			(start -0.12065 0.3048)
			(end -0.67945 0.3048)
			(stroke
				(width 0.1)
				(type default)
			)
			(layer "F.Fab")
		)
		(fp_line
			(start 0.120396 0.3048)
			(end 0.120396 0.2794)
			(stroke
				(width 0.1)
				(type default)
			)
			(layer "F.Fab")
		)
		(fp_line
			(start 0.67945 0.3048)
			(end 0.120396 0.3048)
			(stroke
				(width 0.1)
				(type default)
			)
			(layer "F.Fab")
		)
		(fp_line
			(start -0.12065 0.2794)
			(end -0.12065 0.3048)
			(stroke
				(width 0.1)
				(type default)
			)
			(layer "F.Fab")
		)
		(fp_line
			(start 0.120396 0.2794)
			(end -0.12065 0.2794)
			(stroke
				(width 0.1)
				(type default)
			)
			(layer "F.Fab")
		)
		(fp_line
			(start -0.12065 -0.2794)
			(end 0.12065 -0.2794)
			(stroke
				(width 0.1)
				(type default)
			)
			(layer "F.Fab")
		)
		(fp_line
			(start 0.12065 -0.2794)
			(end 0.12065 -0.3048)
			(stroke
				(width 0.1)
				(type default)
			)
			(layer "F.Fab")
		)
		(fp_line
			(start 0.12065 -0.3048)
			(end 0.67945 -0.3048)
			(stroke
				(width 0.1)
				(type default)
			)
			(layer "F.Fab")
		)
		(fp_line
			(start 0.67945 -0.3048)
			(end 0.67945 0.3048)
			(stroke
				(width 0.1)
				(type default)
			)
			(layer "F.Fab")
		)
		(fp_line
			(start -0.67945 -0.305054)
			(end -0.12065 -0.305054)
			(stroke
				(width 0.1)
				(type default)
			)
			(layer "F.Fab")
		)
		(fp_line
			(start -0.12065 -0.305054)
			(end -0.12065 -0.2794)
			(stroke
				(width 0.1)
				(type default)
			)
			(layer "F.Fab")
		)
		(pad "1" smd circle
			(at -0.40005 0 270)
			(size 0 0)
			(layers "F.Cu" "F.Mask" "F.Paste")
			(net "PVNN_TERM_CPU1")
		)
		(pad "2" smd circle
			(at 0.40005 0 270)
			(size 0 0)
			(layers "F.Cu" "F.Mask" "F.Paste")
			(net "H_CPU1_THERMTRIP_LVC1_R_N")
		)
	)
	(footprint ""
		(layer "F.Cu")
		(at 28.532328 -99.586034)
		(property "Reference" "R3863"
			(at 0 0 0)
			(layer "F.SilkS")
			(hide yes)
			(effects
				(font
					(size 1.27 1.27)
				)
			)
		)
		(property "Value" ""
			(at 0 0 0)
			(layer "F.Fab")
			(effects
				(font
					(size 1.27 1.27)
				)
			)
		)
		(duplicate_pad_numbers_are_jumpers no)
		(fp_line
			(start -0.7874 -0.4064)
			(end 0.7874 -0.4064)
			(stroke
				(width 0.1524)
				(type default)
			)
			(layer "F.SilkS")
		)
		(fp_line
			(start -0.7874 0.4064)
			(end -0.7874 -0.4064)
			(stroke
				(width 0.1524)
				(type default)
			)
			(layer "F.SilkS")
		)
		(fp_line
			(start 0.7874 -0.4064)
			(end 0.7874 0.4064)
			(stroke
				(width 0.1524)
				(type default)
			)
			(layer "F.SilkS")
		)
		(fp_line
			(start 0.7874 0.4064)
			(end -0.7874 0.4064)
			(stroke
				(width 0.1524)
				(type default)
			)
			(layer "F.SilkS")
		)
		(fp_line
			(start -0.67945 -0.305054)
			(end -0.12065 -0.305054)
			(stroke
				(width 0.1)
				(type default)
			)
			(layer "F.Fab")
		)
		(fp_line
			(start -0.67945 0.3048)
			(end -0.67945 -0.305054)
			(stroke
				(width 0.1)
				(type default)
			)
			(layer "F.Fab")
		)
		(fp_line
			(start -0.12065 -0.305054)
			(end -0.12065 -0.2794)
			(stroke
				(width 0.1)
				(type default)
			)
			(layer "F.Fab")
		)
		(fp_line
			(start -0.12065 -0.2794)
			(end 0.12065 -0.2794)
			(stroke
				(width 0.1)
				(type default)
			)
			(layer "F.Fab")
		)
		(fp_line
			(start -0.12065 0.2794)
			(end -0.12065 0.3048)
			(stroke
				(width 0.1)
				(type default)
			)
			(layer "F.Fab")
		)
		(fp_line
			(start -0.12065 0.3048)
			(end -0.67945 0.3048)
			(stroke
				(width 0.1)
				(type default)
			)
			(layer "F.Fab")
		)
		(fp_line
			(start 0.120396 0.2794)
			(end -0.12065 0.2794)
			(stroke
				(width 0.1)
				(type default)
			)
			(layer "F.Fab")
		)
		(fp_line
			(start 0.120396 0.3048)
			(end 0.120396 0.2794)
			(stroke
				(width 0.1)
				(type default)
			)
			(layer "F.Fab")
		)
		(fp_line
			(start 0.12065 -0.3048)
			(end 0.67945 -0.3048)
			(stroke
				(width 0.1)
				(type default)
			)
			(layer "F.Fab")
		)
		(fp_line
			(start 0.12065 -0.2794)
			(end 0.12065 -0.3048)
			(stroke
				(width 0.1)
				(type default)
			)
			(layer "F.Fab")
		)
		(fp_line
			(start 0.67945 -0.3048)
			(end 0.67945 0.3048)
			(stroke
				(width 0.1)
				(type default)
			)
			(layer "F.Fab")
		)
		(fp_line
			(start 0.67945 0.3048)
			(end 0.120396 0.3048)
			(stroke
				(width 0.1)
				(type default)
			)
			(layer "F.Fab")
		)
		(pad "1" smd rect
			(at -0.40005 0 180)
			(size 0.4572 0.508)
			(layers "F.Cu" "F.Mask" "F.Paste")
			(net "P12V_OCP_SFF_ISENSE_MAM_MAM")
		)
		(pad "2" smd rect
			(at 0.40005 0 180)
			(size 0.4572 0.508)
			(layers "F.Cu" "F.Mask" "F.Paste")
			(net "P12V_OCP_SFF_ISENSE_MAM")
		)
	)
	(footprint ""
		(layer "F.Cu")
		(at 90.086688 -65.193672 -90)
		(property "Reference" "R3069"
			(at 0 0 270)
			(layer "F.SilkS")
			(hide yes)
			(effects
				(font
					(size 1.27 1.27)
				)
			)
		)
		(property "Value" ""
			(at 0 0 270)
			(layer "F.Fab")
			(effects
				(font
					(size 1.27 1.27)
				)
			)
		)
		(duplicate_pad_numbers_are_jumpers no)
		(fp_line
			(start -0.7874 0.4064)
			(end -0.7874 -0.4064)
			(stroke
				(width 0.1524)
				(type default)
			)
			(layer "F.SilkS")
		)
		(fp_line
			(start 0.7874 0.4064)
			(end -0.7874 0.4064)
			(stroke
				(width 0.1524)
				(type default)
			)
			(layer "F.SilkS")
		)
		(fp_line
			(start -0.7874 -0.4064)
			(end 0.7874 -0.4064)
			(stroke
				(width 0.1524)
				(type default)
			)
			(layer "F.SilkS")
		)
		(fp_line
			(start 0.7874 -0.4064)
			(end 0.7874 0.4064)
			(stroke
				(width 0.1524)
				(type default)
			)
			(layer "F.SilkS")
		)
		(fp_line
			(start -0.67945 0.3048)
			(end -0.67945 -0.305054)
			(stroke
				(width 0.1)
				(type default)
			)
			(layer "F.Fab")
		)
		(fp_line
			(start -0.12065 0.3048)
			(end -0.67945 0.3048)
			(stroke
				(width 0.1)
				(type default)
			)
			(layer "F.Fab")
		)
		(fp_line
			(start 0.120396 0.3048)
			(end 0.120396 0.2794)
			(stroke
				(width 0.1)
				(type default)
			)
			(layer "F.Fab")
		)
		(fp_line
			(start 0.67945 0.3048)
			(end 0.120396 0.3048)
			(stroke
				(width 0.1)
				(type default)
			)
			(layer "F.Fab")
		)
		(fp_line
			(start -0.12065 0.2794)
			(end -0.12065 0.3048)
			(stroke
				(width 0.1)
				(type default)
			)
			(layer "F.Fab")
		)
		(fp_line
			(start 0.120396 0.2794)
			(end -0.12065 0.2794)
			(stroke
				(width 0.1)
				(type default)
			)
			(layer "F.Fab")
		)
		(fp_line
			(start -0.12065 -0.2794)
			(end 0.12065 -0.2794)
			(stroke
				(width 0.1)
				(type default)
			)
			(layer "F.Fab")
		)
		(fp_line
			(start 0.12065 -0.2794)
			(end 0.12065 -0.3048)
			(stroke
				(width 0.1)
				(type default)
			)
			(layer "F.Fab")
		)
		(fp_line
			(start 0.12065 -0.3048)
			(end 0.67945 -0.3048)
			(stroke
				(width 0.1)
				(type default)
			)
			(layer "F.Fab")
		)
		(fp_line
			(start 0.67945 -0.3048)
			(end 0.67945 0.3048)
			(stroke
				(width 0.1)
				(type default)
			)
			(layer "F.Fab")
		)
		(fp_line
			(start -0.67945 -0.305054)
			(end -0.12065 -0.305054)
			(stroke
				(width 0.1)
				(type default)
			)
			(layer "F.Fab")
		)
		(fp_line
			(start -0.12065 -0.305054)
			(end -0.12065 -0.2794)
			(stroke
				(width 0.1)
				(type default)
			)
			(layer "F.Fab")
		)
		(pad "1" smd circle
			(at -0.40005 0 270)
			(size 0 0)
			(layers "F.Cu" "F.Mask" "F.Paste")
			(net "LED_PWRGD_SYS_PWROK_R")
		)
		(pad "2" smd circle
			(at 0.40005 0 270)
			(size 0 0)
			(layers "F.Cu" "F.Mask" "F.Paste")
			(net "P3V3_AUX")
		)
	)
	(footprint ""
		(layer "F.Cu")
		(at 148.197824 -52.420012)
		(property "Reference" "R3623"
			(at 0 0 0)
			(layer "F.SilkS")
			(hide yes)
			(effects
				(font
					(size 1.27 1.27)
				)
			)
		)
		(property "Value" ""
			(at 0 0 0)
			(layer "F.Fab")
			(effects
				(font
					(size 1.27 1.27)
				)
			)
		)
		(duplicate_pad_numbers_are_jumpers no)
		(fp_line
			(start -0.7874 -0.4064)
			(end 0.7874 -0.4064)
			(stroke
				(width 0.1524)
				(type default)
			)
			(layer "F.SilkS")
		)
		(fp_line
			(start -0.7874 0.4064)
			(end -0.7874 -0.4064)
			(stroke
				(width 0.1524)
				(type default)
			)
			(layer "F.SilkS")
		)
		(fp_line
			(start 0.7874 -0.4064)
			(end 0.7874 0.4064)
			(stroke
				(width 0.1524)
				(type default)
			)
			(layer "F.SilkS")
		)
		(fp_line
			(start 0.7874 0.4064)
			(end -0.7874 0.4064)
			(stroke
				(width 0.1524)
				(type default)
			)
			(layer "F.SilkS")
		)
		(fp_line
			(start -0.67945 -0.305054)
			(end -0.12065 -0.305054)
			(stroke
				(width 0.1)
				(type default)
			)
			(layer "F.Fab")
		)
		(fp_line
			(start -0.67945 0.3048)
			(end -0.67945 -0.305054)
			(stroke
				(width 0.1)
				(type default)
			)
			(layer "F.Fab")
		)
		(fp_line
			(start -0.12065 -0.305054)
			(end -0.12065 -0.2794)
			(stroke
				(width 0.1)
				(type default)
			)
			(layer "F.Fab")
		)
		(fp_line
			(start -0.12065 -0.2794)
			(end 0.12065 -0.2794)
			(stroke
				(width 0.1)
				(type default)
			)
			(layer "F.Fab")
		)
		(fp_line
			(start -0.12065 0.2794)
			(end -0.12065 0.3048)
			(stroke
				(width 0.1)
				(type default)
			)
			(layer "F.Fab")
		)
		(fp_line
			(start -0.12065 0.3048)
			(end -0.67945 0.3048)
			(stroke
				(width 0.1)
				(type default)
			)
			(layer "F.Fab")
		)
		(fp_line
			(start 0.120396 0.2794)
			(end -0.12065 0.2794)
			(stroke
				(width 0.1)
				(type default)
			)
			(layer "F.Fab")
		)
		(fp_line
			(start 0.120396 0.3048)
			(end 0.120396 0.2794)
			(stroke
				(width 0.1)
				(type default)
			)
			(layer "F.Fab")
		)
		(fp_line
			(start 0.12065 -0.3048)
			(end 0.67945 -0.3048)
			(stroke
				(width 0.1)
				(type default)
			)
			(layer "F.Fab")
		)
		(fp_line
			(start 0.12065 -0.2794)
			(end 0.12065 -0.3048)
			(stroke
				(width 0.1)
				(type default)
			)
			(layer "F.Fab")
		)
		(fp_line
			(start 0.67945 -0.3048)
			(end 0.67945 0.3048)
			(stroke
				(width 0.1)
				(type default)
			)
			(layer "F.Fab")
		)
		(fp_line
			(start 0.67945 0.3048)
			(end 0.120396 0.3048)
			(stroke
				(width 0.1)
				(type default)
			)
			(layer "F.Fab")
		)
		(pad "1" smd circle
			(at -0.40005 0)
			(size 0 0)
			(layers "F.Cu" "F.Mask" "F.Paste")
			(net "P3V3_AUX")
		)
		(pad "2" smd circle
			(at 0.40005 0)
			(size 0 0)
			(layers "F.Cu" "F.Mask" "F.Paste")
			(net "INA230_4_A1")
		)
	)
	(footprint ""
		(layer "F.Cu")
		(at 19.769582 -423.629836 -90)
		(property "Reference" "R3499"
			(at 0 0 270)
			(layer "F.SilkS")
			(hide yes)
			(effects
				(font
					(size 1.27 1.27)
				)
			)
		)
		(property "Value" ""
			(at 0 0 270)
			(layer "F.Fab")
			(effects
				(font
					(size 1.27 1.27)
				)
			)
		)
		(duplicate_pad_numbers_are_jumpers no)
		(fp_line
			(start -0.7874 0.4064)
			(end -0.7874 -0.4064)
			(stroke
				(width 0.1524)
				(type default)
			)
			(layer "F.SilkS")
		)
		(fp_line
			(start 0.7874 0.4064)
			(end -0.7874 0.4064)
			(stroke
				(width 0.1524)
				(type default)
			)
			(layer "F.SilkS")
		)
		(fp_line
			(start -0.7874 -0.4064)
			(end 0.7874 -0.4064)
			(stroke
				(width 0.1524)
				(type default)
			)
			(layer "F.SilkS")
		)
		(fp_line
			(start 0.7874 -0.4064)
			(end 0.7874 0.4064)
			(stroke
				(width 0.1524)
				(type default)
			)
			(layer "F.SilkS")
		)
		(fp_line
			(start -0.67945 0.3048)
			(end -0.67945 -0.305054)
			(stroke
				(width 0.1)
				(type default)
			)
			(layer "F.Fab")
		)
		(fp_line
			(start -0.12065 0.3048)
			(end -0.67945 0.3048)
			(stroke
				(width 0.1)
				(type default)
			)
			(layer "F.Fab")
		)
		(fp_line
			(start 0.120396 0.3048)
			(end 0.120396 0.2794)
			(stroke
				(width 0.1)
				(type default)
			)
			(layer "F.Fab")
		)
		(fp_line
			(start 0.67945 0.3048)
			(end 0.120396 0.3048)
			(stroke
				(width 0.1)
				(type default)
			)
			(layer "F.Fab")
		)
		(fp_line
			(start -0.12065 0.2794)
			(end -0.12065 0.3048)
			(stroke
				(width 0.1)
				(type default)
			)
			(layer "F.Fab")
		)
		(fp_line
			(start 0.120396 0.2794)
			(end -0.12065 0.2794)
			(stroke
				(width 0.1)
				(type default)
			)
			(layer "F.Fab")
		)
		(fp_line
			(start -0.12065 -0.2794)
			(end 0.12065 -0.2794)
			(stroke
				(width 0.1)
				(type default)
			)
			(layer "F.Fab")
		)
		(fp_line
			(start 0.12065 -0.2794)
			(end 0.12065 -0.3048)
			(stroke
				(width 0.1)
				(type default)
			)
			(layer "F.Fab")
		)
		(fp_line
			(start 0.12065 -0.3048)
			(end 0.67945 -0.3048)
			(stroke
				(width 0.1)
				(type default)
			)
			(layer "F.Fab")
		)
		(fp_line
			(start 0.67945 -0.3048)
			(end 0.67945 0.3048)
			(stroke
				(width 0.1)
				(type default)
			)
			(layer "F.Fab")
		)
		(fp_line
			(start -0.67945 -0.305054)
			(end -0.12065 -0.305054)
			(stroke
				(width 0.1)
				(type default)
			)
			(layer "F.Fab")
		)
		(fp_line
			(start -0.12065 -0.305054)
			(end -0.12065 -0.2794)
			(stroke
				(width 0.1)
				(type default)
			)
			(layer "F.Fab")
		)
		(pad "1" smd circle
			(at -0.40005 0 270)
			(size 0 0)
			(layers "F.Cu" "F.Mask" "F.Paste")
			(net "GPU_BASE_ID1")
		)
		(pad "2" smd circle
			(at 0.40005 0 270)
			(size 0 0)
			(layers "F.Cu" "F.Mask" "F.Paste")
			(net "GPU_BASE_ID1_R")
		)
	)
	(footprint ""
		(layer "F.Cu")
		(at 377.541282 -59.295792 180)
		(property "Reference" "R747"
			(at 0 0 180)
			(layer "F.SilkS")
			(hide yes)
			(effects
				(font
					(size 1.27 1.27)
				)
			)
		)
		(property "Value" ""
			(at 0 0 180)
			(layer "F.Fab")
			(effects
				(font
					(size 1.27 1.27)
				)
			)
		)
		(duplicate_pad_numbers_are_jumpers no)
		(fp_line
			(start 0.7874 0.4064)
			(end -0.7874 0.4064)
			(stroke
				(width 0.1524)
				(type default)
			)
			(layer "F.SilkS")
		)
		(fp_line
			(start 0.7874 -0.4064)
			(end 0.7874 0.4064)
			(stroke
				(width 0.1524)
				(type default)
			)
			(layer "F.SilkS")
		)
		(fp_line
			(start -0.7874 0.4064)
			(end -0.7874 -0.4064)
			(stroke
				(width 0.1524)
				(type default)
			)
			(layer "F.SilkS")
		)
		(fp_line
			(start -0.7874 -0.4064)
			(end 0.7874 -0.4064)
			(stroke
				(width 0.1524)
				(type default)
			)
			(layer "F.SilkS")
		)
		(fp_line
			(start 0.67945 0.3048)
			(end 0.120396 0.3048)
			(stroke
				(width 0.1)
				(type default)
			)
			(layer "F.Fab")
		)
		(fp_line
			(start 0.67945 -0.3048)
			(end 0.67945 0.3048)
			(stroke
				(width 0.1)
				(type default)
			)
			(layer "F.Fab")
		)
		(fp_line
			(start 0.12065 -0.2794)
			(end 0.12065 -0.3048)
			(stroke
				(width 0.1)
				(type default)
			)
			(layer "F.Fab")
		)
		(fp_line
			(start 0.12065 -0.3048)
			(end 0.67945 -0.3048)
			(stroke
				(width 0.1)
				(type default)
			)
			(layer "F.Fab")
		)
		(fp_line
			(start 0.120396 0.3048)
			(end 0.120396 0.2794)
			(stroke
				(width 0.1)
				(type default)
			)
			(layer "F.Fab")
		)
		(fp_line
			(start 0.120396 0.2794)
			(end -0.12065 0.2794)
			(stroke
				(width 0.1)
				(type default)
			)
			(layer "F.Fab")
		)
		(fp_line
			(start -0.12065 0.3048)
			(end -0.67945 0.3048)
			(stroke
				(width 0.1)
				(type default)
			)
			(layer "F.Fab")
		)
		(fp_line
			(start -0.12065 0.2794)
			(end -0.12065 0.3048)
			(stroke
				(width 0.1)
				(type default)
			)
			(layer "F.Fab")
		)
		(fp_line
			(start -0.12065 -0.2794)
			(end 0.12065 -0.2794)
			(stroke
				(width 0.1)
				(type default)
			)
			(layer "F.Fab")
		)
		(fp_line
			(start -0.12065 -0.305054)
			(end -0.12065 -0.2794)
			(stroke
				(width 0.1)
				(type default)
			)
			(layer "F.Fab")
		)
		(fp_line
			(start -0.67945 0.3048)
			(end -0.67945 -0.305054)
			(stroke
				(width 0.1)
				(type default)
			)
			(layer "F.Fab")
		)
		(fp_line
			(start -0.67945 -0.305054)
			(end -0.12065 -0.305054)
			(stroke
				(width 0.1)
				(type default)
			)
			(layer "F.Fab")
		)
		(pad "1" smd circle
			(at -0.40005 0 180)
			(size 0 0)
			(layers "F.Cu" "F.Mask" "F.Paste")
			(net "P1V05_PCH_AUX")
		)
		(pad "2" smd circle
			(at 0.40005 0 180)
			(size 0 0)
			(layers "F.Cu" "F.Mask" "F.Paste")
			(net "JTAG_DBP_TDO_PCH")
		)
	)
)
